FILE_TYPE = CONNECTIVITY;
{Allegro Design Entry HDL 16.6-p007 (v16-6-112F) 10/10/2012}
"PAGE_NUMBER" = 121;
0"NC";
1"GND\g";
2"P3V3_STBY\g";
3"GND\g";
4"FM_SINT_PRSNT_N";
5"RST_SRTCRST_N";
6"H_CPU0_MEMABC_MEMHOT_PCH_N";
7"FM_CPU_ERR1_PCH_N";
8"RMII_BMC_PCH_SPRNGVLLE_TXD0";
9"SPI_PCH_TPM_CS_N";
10"RMII_SPRNGVLLE_BMC_PCH_RXD0_R1";
11"RMII_SPRNGVLLE_BMC_PCH_RXD1_R1";
12"RMII_BMC_PCH_SPRNGVLLE_CRSDV_R1";
13"RMII_PCH_SPRNGVLLE_ARB_OUT_R";
14"RMII_BMC_PCH_SPRNGVLLE_RXER_R";
15"RMII_BMC_PCH_SPRNGVLLE_RXER";
16"RMII_PCH_SPRNGVLLE_ARB_OUT";
17"RMII_BMC_PCH_SPRNGVLLE_CRSDV";
18"RMII_SPRNGVLLE_BMC_PCH_RXD1";
19"RMII_SPRNGVLLE_BMC_PCH_RXD0";
20"FM_INTRUDER_HDR_PCH_N";
21"FM_OCP_MEZZC_PRES_1V05_PCH_N";
22"FM_OCP_MEZZB_PRES_1V05_PCH_N";
23"TP_PCH_HDA_SDI_1";
24"FM_FLASH_DESC_OVERRIDE";
25"SPI_PCH_MISO";
26"SPI_PCH_IO2";
27"SPI_PCH_IO3";
28"SPI_PCH_CLK";
29"SPI_PCH_CS0_R_N";
30"SPI_PCH_MOSI_R";
31"FM_PCH_PRSNT_N";
32"TP_PCH_DISPA_SDO";
33"TP_PCH_DISPA_SDI";
34"TP_PCH_DISPA_BCLK";
35"TP_PCH_HDA_SYNC";
36"TP_PCH_HSA_RST_N";
37"TP_PCH_HDA_BCLK";
38"RST_RTCRST_N";
39"TP_PCH_RSVD9";
40"FM_PRSNT_2_6_N";
41"FM_PRSNT_2_5_N";
42"FM_PRSNT_2_4_N";
43"FM_PRSNT_2_3_N";
44"FM_PRSNT_2_2_N";
45"FM_PRSNT_2_1_N";
46"FM_CPU_ERR0_PCH_N";
47"H_CPU1_MEMKLM_MEMHOT_PCH_N";
48"FM_CPU0_PROCHOT_PCH_N";
49"FM_CPU1_PROCHOT_PCH_N";
50"H_CPU1_MEMGHJ_MEMHOT_PCH_N";
51"H_CPU0_MEMDEF_MEMHOT_PCH_N";
52"TP_PCH_RSVD25";
53"TP_PCH_GPP_L11";
54"TP_PCH_GPP_L10";
55"TP_PCH_RSVD24";
56"RMII_SPRNGVLLE_BMC_PCH_RXD1_R1";
57"RMII_SPRNGVLLE_BMC_PCH_RXD0_R1";
58"RMII_BMC_PCH_SPRNGVLLE_TXD1";
59"CLK_50M_CKMNG_PCH_10GBE";
60"RMII_BMC_PCH_SPRNGVLLE_TXEN";
61"RMII_BMC_PCH_SPRNGVLLE_CRSDV_R1";
62"A_1P8_3P3_RCOMP";
63"CLK_50M_CKMNG_PCH_10GBE";
64"RMII_BMC_PCH_SPRNGVLLE_RXER_R";
65"RMII_PCH_SPRNGVLLE_ARB_IN";
66"RMII_PCH_SPRNGVLLE_ARB_OUT_R";
67"TP_PCH_RSVD16";
68"RST_PCIE_PCH_PERST_N";
69"TP_PCH_RSVD14";
70"TP_PCH_RSVD13";
71"TP_PCH_RSVD4";
72"TP_PCH_RSVD15";
73"TP_PCH_RSVD17";
74"TP_PCH_RSVD18";
75"TP_PCH_RSVD19";
76"TP_PCH_RSVD22";
77"TP_PCH_RSVD20";
78"TP_PCH_RSVD21";
79"TP_PCH_RSVD23";
80"TP_PCH_RSVD0";
81"TP_PCH_RSVD1";
82"TP_PCH_RSVD2";
83"TP_PCH_RSVD3";
84"TP_PCH_RSVD5";
85"TP_PCH_RSVD6";
86"TP_PCH_RSVD7";
87"TP_PCH_RSVD8";
88"TP_PCH_RSVD12";
89"TP_PCH_HDA_SDI_0";
90"TP_SPI_PCH_CS1_R1_N";
91"TP_PCH_RSVD26";
92"TP_PCH_RSVD27";
93"TP_PCH_RSVD46";
94"FM_WBG_PRSNT_N";
95"SPI_PCH_MOSI";
96"SPI_PCH_CS0_N";
%"RES"
"1","(-5100,1175)","0","mstr_discrete","I101";
;
TOLERANCE"1%"
VALUE"33.2"
LOCATION"R8D11"
PART_NUMBER"G21796-074"
WATTAGE"1/16W"
PACK_TYPE"0402"
MATERIAL"CHIP"
CDS_SEC"1"
CDS_LOCATION"R8D11"
SEC"1"
SEC_TYPE"0402"
CDS_LIB"mstr_discrete"
ROOM"SB";
"B"
$PN"2"13;
"A"
$PN"1"16;
%"RES"
"1","(-1925,3150)","0","mstr_discrete","I31";
;
WATTAGE"1/16W"
MATERIAL"CHIP"
PACK_TYPE"0402"
TOLERANCE"5%"
LOCATION"R7C15"
PART_NUMBER"G21497-005"
VALUE"0.0"
CDS_LOCATION"R7C15"
$SEC"1"
CDS_SEC"1"
CDS_LIB"mstr_discrete"
ROOM"SB";
"B"
$PN"2"95;
"A"
$PN"1"30;
%"RES"
"1","(-1950,3550)","0","mstr_discrete","I33";
;
PACK_TYPE"0402"
MATERIAL"CHIP"
TOLERANCE"1%"
LOCATION"R7C16"
PART_NUMBER"G21796-074"
WATTAGE"1/16W"
VALUE"33.2"
CDS_LOCATION"R7C16"
$SEC"1"
CDS_SEC"1"
CDS_LIB"mstr_discrete"
ROOM"SB";
"B"
$PN"2"96;
"A"
$PN"1"29;
%"LBG_CORE_QAT_EXT_D"
"8","(-4050,2800)","0","mstr_u_proc","I34";
;
CDS_SEC"8"
MATERIAL"IC"
LOCATION"U7C1"
PART_NUMBER"H91415-002"
SEC_TYPE"BGA1"
SEC"8"
CDS_LIB"mstr_u_proc"
BOM_COST"SB"
CDS_LOCATION"U7C1"
ROOM"SB"
PACK_TYPE"BGA1";
"CGC_DUT_DETECT_N"
$PN"C70"31;
"GPIO_RCOMP_1P8_3P3"
$PN"AM4"62;
"GPP_K0_LAN_NCSI_CLK_IN"
$PN"AJ1"59;
"GPP_K10_PE_RST_N"
$PN"AH4"68;
"GPP_K1_LAN_NCSI_TXD0"
$PN"AM2"8;
"GPP_K2_LAN_NCSI_TXD1"
$PN"AK2"58;
"GPP_K3_LAN_NCSI_TX_EN"
$PN"AL3"60;
"GPP_K4_LAN_NCSI_CRS_DV"
$PN"AN3"61;
"GPP_K5_LAN_NCSI_RXD0"
$PN"AL1"57;
"GPP_K6_LAN_NCSI_RXD1"
$PN"AN1"56;
"GPP_K7"
$PN"AH2"64;
"GPP_K8_LAN_NCSI_ARB_IN"
$PN"AJ3"65;
"GPP_K9_LAN_NCSI_ARB_OUT"
$PN"AK4"66;
"GPP_L10_TESTCH0_CLK"
$PN"AF20"54;
"GPP_L11_TESTCH1_D0"
$PN"AD20"53;
"GPP_L12_TESTCH1_D1"
$PN"Y15"6;
"GPP_L13_TESTCH1_D2"
$PN"AD13"51;
"GPP_L14_TESTCH1_D3"
$PN"AA13"50;
"GPP_L15_TESTCH1_D4"
$PN"Y11"47;
"GPP_L16_TESTCH1_D5"
$PN"Y7"48;
"GPP_L17_TESTCH1_D6"
$PN"AA9"49;
"GPP_L18_TESTCH1_D7"
$PN"AE7"46;
"GPP_L19_TESTCH1_CLK"
$PN"AG11"7;
"GPP_L2_TESTCH0_D0"
$PN"AE18"45;
"GPP_L3_TESTCH0_D1"
$PN"AE15"44;
"GPP_L4_TESTCH0_D2"
$PN"AE11"43;
"GPP_L5_TESTCH0_D3"
$PN"Y18"42;
"GPP_L6_TESTCH0_D4"
$PN"AA20"41;
"GPP_L7_TESTCH0_D5"
$PN"AA17"40;
"GPP_L8_TESTCH0_D6"
$PN"AD9"22;
"GPP_L9_TESTCH0_D7"
$PN"AD17"21;
"HDA_BCLK"
$PN"P18"37;
"HDA_RST_N"
$PN"M18"36;
"HDA_SDI_0"
$PN"K20"89;
"HDA_SDI_1"
$PN"V18"23;
"HDA_SDO"
$PN"U24"24;
"HDA_SYNC"
$PN"H20"35;
"INTRUDER_N"
$PN"AG18"20;
"RSVD<68>"
$PN"V22"32;
"RSVD<67>"
$PN"R20"33;
"RSVD<66>"
$PN"U20"34;
"RSVD<46>"
$PN"BW3"93;
"RSVD<27>"
$PN"BG26"92;
"RSVD<26>"
$PN"BH24"91;
"RSVD<25>"
$PN"P48"52;
"RSVD<24>"
$PN"P44"55;
"RSVD<23>"
$PN"P40"79;
"RSVD<22>"
$PN"AT71"76;
"RSVD<21>"
$PN"A11"78;
"RSVD<20>"
$PN"D10"77;
"RSVD<19>"
$PN"C9"75;
"RSVD<18>"
$PN"C11"74;
"RSVD<17>"
$PN"B10"73;
"RSVD<16>"
$PN"C5"67;
"RSVD<15>"
$PN"C6"72;
"RSVD<14>"
$PN"E18"69;
"RSVD<13>"
$PN"C67"70;
"RSVD<12>"
$PN"C68"88;
"RSVD<11>"
$PN"C18"4;
"RSVD<10>"
$PN"D8"94;
"RSVD<9>"
$PN"F66"39;
"RSVD<8>"
$PN"F69"87;
"RSVD<7>"
$PN"F8"86;
"RSVD<6>"
$PN"AT69"85;
"RSVD<5>"
$PN"AG15"84;
"RSVD<4>"
$PN"P37"71;
"RSVD<3>"
$PN"V11"83;
"RSVD<2>"
$PN"AA58"82;
"RSVD<1>"
$PN"AC56"81;
"RSVD<0>"
$PN"AF61"80;
"RTCRST_N"
$PN"P11"38;
"SPI0_CLK"
$PN"K2"28;
"SPI0_FLASH_CS0_N"
$PN"J3"29;
"SPI0_FLASH_CS1_N"
$PN"G7"90;
"SPI0_IO2"
$PN"F5"26;
"SPI0_IO3"
$PN"L1"27;
"SPI0_MISO_IO1"
$PN"L3"25;
"SPI0_MOSI_IO0"
$PN"H4"30;
"SPI0_TPM_CS_N"
$PN"K4"9;
"SRTCRST_N"
$PN"G18"5;
%"RES"
"2","(-7750,3675)","0","mstr_discrete","I35";
;
CDS_SEC"1"
LOCATION"R8C26"
PACK_TYPE"0402"
TOLERANCE"1%"
VALUE"100.0"
WATTAGE"1/16W"
MATERIAL"CHIP"
PART_NUMBER"G21796-017"
CDS_LIB"mstr_discrete"
SEC"1"
SEC_TYPE"0402"
ROOM"SB"
CDS_LOCATION"R8C26";
"A"
$PN"1"62;
"B"
$PN"2"1;
%"RES"
"2","(-8075,2525)","0","mstr_discrete","I37";
;
CDS_SEC"1"
PACK_TYPE"0402"
WATTAGE"1/16W"
MATERIAL"CHIP"
TOLERANCE"1%"
VALUE"10.0K"
LOCATION"R3N10"
PART_NUMBER"G21796-016"
CDS_LOCATION"R3N10"
SEC"1"
SEC_TYPE"0402"
CDS_LIB"mstr_discrete"
ROOM"SB";
"A"
$PN"1"2;
"B"
$PN"2"20;
%"GND"
"1","(-7750,3450)","0","mstr_symbols","I39";
;
BODY_TYPE"PLUMBING"
CDS_LIB"mstr_symbols"
SIZE"1B"
HDL_POWER"GND"
VOLTAGE"0.0V";
"A\NAC"1;
%"P3V3_STBY"
"1","(-8075,2750)","0","mstr_symbols","I40";
;
CDS_LIB"mstr_symbols"
SIZE"1B"
BODY_TYPE"PLUMBING"
HDL_POWER"P3V3_STBY"
VOLTAGE"3.3V";
"G\NAC"2;
%"RES"
"2","(-8125,950)","0","mstr_discrete","I73";
;
CDS_SEC"1"
LOCATION"R7C20"
PACK_TYPE"0402"
TOLERANCE"1%"
VALUE"10.0K"
PART_NUMBER"G21796-016"
MATERIAL"CHIP"
WATTAGE"1/16W"
CDS_LIB"mstr_discrete"
SEC_TYPE"0402"
BOM_COST"NT_GBE_BASE"
SEC"1"
CDS_LOCATION"R7C20"
ROOM"NIC_SPRV";
"A"
$PN"1"63;
"B"
$PN"2"3;
%"GND"
"1","(-8125,675)","0","mstr_symbols","I74";
;
BODY_TYPE"PLUMBING"
CDS_LIB"mstr_symbols"
SIZE"1B"
HDL_POWER"GND"
VOLTAGE"0.0V";
"A\NAC"3;
%"RES"
"1","(-5100,550)","0","mstr_discrete","I89";
;
TOLERANCE"5%"
VALUE"0.0"
LOCATION"R3P3"
PACK_TYPE"0402"
MATERIAL"CHIP"
PART_NUMBER"G21497-005"
WATTAGE"1/16W"
SEC_TYPE"0402"
CDS_LIB"mstr_discrete"
SEC"1"
CDS_LOCATION"R3P3"
CDS_SEC"1";
"B"
$PN"2"10;
"A"
$PN"1"19;
%"RES"
"1","(-5100,850)","0","mstr_discrete","I90";
;
TOLERANCE"5%"
VALUE"0.0"
LOCATION"R3P2"
PACK_TYPE"0402"
PART_NUMBER"G21497-005"
MATERIAL"CHIP"
WATTAGE"1/16W"
CDS_SEC"1"
CDS_LOCATION"R3P2"
SEC"1"
CDS_LIB"mstr_discrete"
SEC_TYPE"0402";
"B"
$PN"2"12;
"A"
$PN"1"17;
%"RES"
"1","(-5100,700)","0","mstr_discrete","I91";
;
PACK_TYPE"0402"
VALUE"0.0"
LOCATION"R2P1"
TOLERANCE"5%"
PART_NUMBER"G21497-005"
MATERIAL"CHIP"
WATTAGE"1/16W"
SEC_TYPE"0402"
CDS_LIB"mstr_discrete"
SEC"1"
CDS_LOCATION"R2P1"
CDS_SEC"1";
"B"
$PN"2"11;
"A"
$PN"1"18;
%"RES"
"1","(-5100,1025)","0","mstr_discrete","I98";
;
TOLERANCE"1%"
VALUE"33.2"
PART_NUMBER"G21796-074"
PACK_TYPE"0402"
MATERIAL"CHIP"
LOCATION"R7C14"
WATTAGE"1/16W"
CDS_SEC"1"
CDS_LOCATION"R7C14"
SEC"1"
SEC_TYPE"0402"
CDS_LIB"mstr_discrete"
ROOM"SB";
"B"
$PN"2"14;
"A"
$PN"1"15;
END.
